(kicad_pcb
	(version 20260206)
	(generator "pcbnew")
	(generator_version "10.0")
	(general
		(thickness 1.6)
		(legacy_teardrops no)
	)
	(paper "A4")
	(title_block
		(title "01162023_DA0F0TEBIF0_F0T_Expander_BD_F_brd_V02_OCP.brd")
		(comment 1 "Grand Teton / footprints 8751-8758 of 9728")
	)
	(layers
		(0 "F.Cu" signal "TOP")
		(4 "In1.Cu" signal "GND")
		(6 "In2.Cu" signal "VCC")
		(8 "In3.Cu" signal "VCC1")
		(10 "In4.Cu" signal "GND1")
		(12 "In5.Cu" signal "IN1")
		(14 "In6.Cu" signal "GND2")
		(16 "In7.Cu" signal "IN2")
		(18 "In8.Cu" signal "GND3")
		(20 "In9.Cu" signal "IN3")
		(22 "In10.Cu" signal "GND4")
		(24 "In11.Cu" signal "IN4")
		(26 "In12.Cu" signal "GND5")
		(28 "In13.Cu" signal "IN5")
		(30 "In14.Cu" signal "GND6")
		(32 "In15.Cu" signal "IN6")
		(34 "In16.Cu" signal "GND7")
		(2 "B.Cu" signal "BOTTOM")
		(9 "F.Adhes" user "F.Adhesive")
		(11 "B.Adhes" user "B.Adhesive")
		(13 "F.Paste" user "Package Geometry/Pastemask Top")
		(15 "B.Paste" user "Package Geometry/Pastemask Bottom")
		(5 "F.SilkS" user "Ref Des/Silkscreen Top")
		(7 "B.SilkS" user "Ref Des/Silkscreen Bottom")
		(1 "F.Mask" user "Board Geometry/Soldermask Top")
		(3 "B.Mask" user "Board Geometry/Soldermask Bottom")
		(17 "Dwgs.User" user "User.Drawings")
		(19 "Cmts.User" user "User.Comments")
		(21 "Eco1.User" user "User.Eco1")
		(23 "Eco2.User" user "User.Eco2")
		(25 "Edge.Cuts" user "Board Geometry/Outline")
		(27 "Margin" user)
		(31 "F.CrtYd" user "Package Geometry/Place Bound Top")
		(29 "B.CrtYd" user "Package Geometry/Place Bound Bottom")
		(35 "F.Fab" user "Ref Des/Assembly Top")
		(33 "B.Fab" user "Ref Des/Assembly Bottom")
	)
	(footprint ""
		(layer "B.Cu")
		(at 373.370602 -243.936012 180)
		(property "Reference" "U101"
			(at 0.102108 -1.873758 0)
			(unlocked yes)
			(layer "B.SilkS")
			(effects
				(font
					(size 0.7874 0.5842)
					(thickness 0.1524)
				)
				(justify mirror)
			)
		)
		(property "Value" ""
			(at 0 0 0)
			(layer "B.Fab")
			(effects
				(font
					(size 1.27 1.27)
				)
				(justify mirror)
			)
		)
		(duplicate_pad_numbers_are_jumpers no)
		(fp_line
			(start 1.7272 1.1176)
			(end 1.7272 -1.1176)
			(stroke
				(width 0.1524)
				(type default)
			)
			(layer "B.SilkS")
		)
		(fp_line
			(start 0.254 -1.1176)
			(end 1.7272 -1.1176)
			(stroke
				(width 0.1524)
				(type default)
			)
			(layer "B.SilkS")
		)
		(fp_line
			(start 0 -0.7366)
			(end 0.254 -1.1176)
			(stroke
				(width 0.1524)
				(type default)
			)
			(layer "B.SilkS")
		)
		(fp_line
			(start -0.254 -1.1176)
			(end 0 -0.7366)
			(stroke
				(width 0.1524)
				(type default)
			)
			(layer "B.SilkS")
		)
		(fp_line
			(start -1.7272 1.1176)
			(end 1.7272 1.1176)
			(stroke
				(width 0.1524)
				(type default)
			)
			(layer "B.SilkS")
		)
		(fp_line
			(start -1.7272 -1.1176)
			(end -0.254 -1.1176)
			(stroke
				(width 0.1524)
				(type default)
			)
			(layer "B.SilkS")
		)
		(fp_line
			(start -1.7272 -1.1176)
			(end -1.7272 1.1176)
			(stroke
				(width 0.1524)
				(type default)
			)
			(layer "B.SilkS")
		)
		(fp_poly
			(pts
				(xy 1.9558 -0.649986) (xy 2.7178 -0.268986) (xy 2.7178 -1.030986)
			)
			(stroke
				(width 0)
				(type default)
			)
			(fill yes)
			(layer "B.SilkS")
		)
		(fp_line
			(start 1.5748 1.1176)
			(end -1.5748 1.1176)
			(stroke
				(width 0.1)
				(type default)
			)
			(layer "B.Fab")
		)
		(fp_line
			(start 1.5748 -1.1176)
			(end 1.5748 1.1176)
			(stroke
				(width 0.1)
				(type default)
			)
			(layer "B.Fab")
		)
		(fp_line
			(start -1.5748 1.1176)
			(end -1.5748 -1.1176)
			(stroke
				(width 0.1)
				(type default)
			)
			(layer "B.Fab")
		)
		(fp_line
			(start -1.5748 -1.1176)
			(end 1.5748 -1.1176)
			(stroke
				(width 0.1)
				(type default)
			)
			(layer "B.Fab")
		)
		(fp_poly
			(pts
				(xy 1.9558 -0.649986) (xy 2.7178 -0.268986) (xy 2.7178 -1.030986)
			)
			(stroke
				(width 0)
				(type default)
			)
			(fill yes)
			(layer "B.Fab")
		)
		(pad "1" smd rect
			(at 0.999998 -0.649986 90)
			(size 0.3556 1.1176)
			(layers "B.Cu" "B.Mask" "B.Paste")
			(net "UART_PEX0_SDB_R_TX")
		)
		(pad "2" smd rect
			(at 0.999998 0 90)
			(size 0.3556 1.1176)
			(layers "B.Cu" "B.Mask" "B.Paste")
			(net "GND")
		)
		(pad "3" smd rect
			(at 0.999998 0.649986 90)
			(size 0.3556 1.1176)
			(layers "B.Cu" "B.Mask" "B.Paste")
			(net "UART_PEX1_SDB_R_TX")
		)
		(pad "4" smd rect
			(at -0.999998 0.649986 90)
			(size 0.3556 1.1176)
			(layers "B.Cu" "B.Mask" "B.Paste")
			(net "UART_PEX1_SDB_BUF_R_TX")
		)
		(pad "5" smd rect
			(at -0.999998 0 90)
			(size 0.3556 1.1176)
			(layers "B.Cu" "B.Mask" "B.Paste")
			(net "P1V8_PEX")
		)
		(pad "6" smd rect
			(at -0.999998 -0.649986 90)
			(size 0.3556 1.1176)
			(layers "B.Cu" "B.Mask" "B.Paste")
			(net "UART_PEX0_SDB_BUF_R_TX")
		)
	)
	(footprint ""
		(layer "B.Cu")
		(at 46.355 -296.37482)
		(property "Reference" "C3029"
			(at 0 0 0)
			(layer "B.SilkS")
			(hide yes)
			(effects
				(font
					(size 1.27 1.27)
				)
				(justify mirror)
			)
		)
		(property "Value" ""
			(at 0 0 0)
			(layer "B.Fab")
			(effects
				(font
					(size 1.27 1.27)
				)
				(justify mirror)
			)
		)
		(duplicate_pad_numbers_are_jumpers no)
		(fp_line
			(start -0.299974 -0.150114)
			(end -0.299974 0.150114)
			(stroke
				(width 0.1)
				(type default)
			)
			(layer "B.Fab")
		)
		(fp_line
			(start -0.299974 0.150114)
			(end 0.299974 0.150114)
			(stroke
				(width 0.1)
				(type default)
			)
			(layer "B.Fab")
		)
		(fp_line
			(start 0.299974 -0.150114)
			(end -0.299974 -0.150114)
			(stroke
				(width 0.1)
				(type default)
			)
			(layer "B.Fab")
		)
		(fp_line
			(start 0.299974 0.150114)
			(end 0.299974 -0.150114)
			(stroke
				(width 0.1)
				(type default)
			)
			(layer "B.Fab")
		)
		(pad "1" smd rect
			(at 0.2667 0 180)
			(size 0.3048 0.381)
			(layers "B.Cu" "B.Mask" "B.Paste")
			(net "PCEPLL2_VDDA18_PEX0")
		)
		(pad "2" smd rect
			(at -0.2667 0 180)
			(size 0.3048 0.381)
			(layers "B.Cu" "B.Mask" "B.Paste")
			(net "GND")
		)
	)
	(footprint ""
		(layer "B.Cu")
		(at 59.167776 -286.18434 90)
		(property "Reference" "C2944"
			(at 0 0 90)
			(layer "B.SilkS")
			(hide yes)
			(effects
				(font
					(size 1.27 1.27)
				)
				(justify mirror)
			)
		)
		(property "Value" ""
			(at 0 0 90)
			(layer "B.Fab")
			(effects
				(font
					(size 1.27 1.27)
				)
				(justify mirror)
			)
		)
		(duplicate_pad_numbers_are_jumpers no)
		(fp_line
			(start 1.2954 -0.5842)
			(end -1.2954 -0.5842)
			(stroke
				(width 0.1524)
				(type default)
			)
			(layer "B.SilkS")
		)
		(fp_line
			(start -1.2954 -0.5842)
			(end -1.2954 0.5842)
			(stroke
				(width 0.1524)
				(type default)
			)
			(layer "B.SilkS")
		)
		(fp_line
			(start 1.2954 0.5842)
			(end 1.2954 -0.5842)
			(stroke
				(width 0.1524)
				(type default)
			)
			(layer "B.SilkS")
		)
		(fp_line
			(start -1.2954 0.5842)
			(end 1.2954 0.5842)
			(stroke
				(width 0.1524)
				(type default)
			)
			(layer "B.SilkS")
		)
		(fp_line
			(start 0.8636 -0.4572)
			(end -0.8636 -0.4572)
			(stroke
				(width 0.1)
				(type default)
			)
			(layer "B.Fab")
		)
		(fp_line
			(start -0.8636 -0.4572)
			(end -0.8636 -0.4064)
			(stroke
				(width 0.1)
				(type default)
			)
			(layer "B.Fab")
		)
		(fp_line
			(start 1.1938 -0.4064)
			(end 0.8636 -0.4064)
			(stroke
				(width 0.1)
				(type default)
			)
			(layer "B.Fab")
		)
		(fp_line
			(start 0.8636 -0.4064)
			(end 0.8636 -0.4572)
			(stroke
				(width 0.1)
				(type default)
			)
			(layer "B.Fab")
		)
		(fp_line
			(start -0.8636 -0.4064)
			(end -1.1938 -0.4064)
			(stroke
				(width 0.1)
				(type default)
			)
			(layer "B.Fab")
		)
		(fp_line
			(start -1.1938 -0.4064)
			(end -1.1938 0.4064)
			(stroke
				(width 0.1)
				(type default)
			)
			(layer "B.Fab")
		)
		(fp_line
			(start 1.1938 0.4064)
			(end 1.1938 -0.4064)
			(stroke
				(width 0.1)
				(type default)
			)
			(layer "B.Fab")
		)
		(fp_line
			(start 0.8636 0.4064)
			(end 1.1938 0.4064)
			(stroke
				(width 0.1)
				(type default)
			)
			(layer "B.Fab")
		)
		(fp_line
			(start -0.8636 0.4064)
			(end -0.8636 0.4572)
			(stroke
				(width 0.1)
				(type default)
			)
			(layer "B.Fab")
		)
		(fp_line
			(start -1.1938 0.4064)
			(end -0.8636 0.4064)
			(stroke
				(width 0.1)
				(type default)
			)
			(layer "B.Fab")
		)
		(fp_line
			(start 0.8636 0.4572)
			(end 0.8636 0.4064)
			(stroke
				(width 0.1)
				(type default)
			)
			(layer "B.Fab")
		)
		(fp_line
			(start -0.8636 0.4572)
			(end 0.8636 0.4572)
			(stroke
				(width 0.1)
				(type default)
			)
			(layer "B.Fab")
		)
		(pad "1" smd rect
			(at 0.7366 0)
			(size 0.7112 0.8128)
			(layers "B.Cu" "B.Mask" "B.Paste")
			(net "P1V25_SERDES_VDDPLL_PEX0")
		)
		(pad "2" smd rect
			(at -0.7366 0)
			(size 0.7112 0.8128)
			(layers "B.Cu" "B.Mask" "B.Paste")
			(net "GND")
		)
	)
	(footprint ""
		(layer "B.Cu")
		(at 137.846816 -212.188806)
		(property "Reference" "C2588"
			(at 0 0 0)
			(layer "B.SilkS")
			(hide yes)
			(effects
				(font
					(size 1.27 1.27)
				)
				(justify mirror)
			)
		)
		(property "Value" ""
			(at 0 0 0)
			(layer "B.Fab")
			(effects
				(font
					(size 1.27 1.27)
				)
				(justify mirror)
			)
		)
		(duplicate_pad_numbers_are_jumpers no)
		(fp_line
			(start -0.7874 -0.4064)
			(end -0.7874 0.4064)
			(stroke
				(width 0.1524)
				(type default)
			)
			(layer "B.SilkS")
		)
		(fp_line
			(start -0.7874 0.4064)
			(end 0.7874 0.4064)
			(stroke
				(width 0.1524)
				(type default)
			)
			(layer "B.SilkS")
		)
		(fp_line
			(start 0.7874 -0.4064)
			(end -0.7874 -0.4064)
			(stroke
				(width 0.1524)
				(type default)
			)
			(layer "B.SilkS")
		)
		(fp_line
			(start 0.7874 0.4064)
			(end 0.7874 -0.4064)
			(stroke
				(width 0.1524)
				(type default)
			)
			(layer "B.SilkS")
		)
		(fp_line
			(start -0.67945 -0.3048)
			(end -0.67945 0.3048)
			(stroke
				(width 0.1)
				(type default)
			)
			(layer "B.Fab")
		)
		(fp_line
			(start -0.67945 0.3048)
			(end -0.120396 0.3048)
			(stroke
				(width 0.1)
				(type default)
			)
			(layer "B.Fab")
		)
		(fp_line
			(start -0.12065 -0.3048)
			(end -0.67945 -0.3048)
			(stroke
				(width 0.1)
				(type default)
			)
			(layer "B.Fab")
		)
		(fp_line
			(start -0.12065 -0.2794)
			(end -0.12065 -0.3048)
			(stroke
				(width 0.1)
				(type default)
			)
			(layer "B.Fab")
		)
		(fp_line
			(start -0.120396 0.2794)
			(end 0.12065 0.2794)
			(stroke
				(width 0.1)
				(type default)
			)
			(layer "B.Fab")
		)
		(fp_line
			(start -0.120396 0.3048)
			(end -0.120396 0.2794)
			(stroke
				(width 0.1)
				(type default)
			)
			(layer "B.Fab")
		)
		(fp_line
			(start 0.12065 -0.305054)
			(end 0.12065 -0.2794)
			(stroke
				(width 0.1)
				(type default)
			)
			(layer "B.Fab")
		)
		(fp_line
			(start 0.12065 -0.2794)
			(end -0.12065 -0.2794)
			(stroke
				(width 0.1)
				(type default)
			)
			(layer "B.Fab")
		)
		(fp_line
			(start 0.12065 0.2794)
			(end 0.12065 0.3048)
			(stroke
				(width 0.1)
				(type default)
			)
			(layer "B.Fab")
		)
		(fp_line
			(start 0.12065 0.3048)
			(end 0.67945 0.3048)
			(stroke
				(width 0.1)
				(type default)
			)
			(layer "B.Fab")
		)
		(fp_line
			(start 0.67945 -0.305054)
			(end 0.12065 -0.305054)
			(stroke
				(width 0.1)
				(type default)
			)
			(layer "B.Fab")
		)
		(fp_line
			(start 0.67945 0.3048)
			(end 0.67945 -0.305054)
			(stroke
				(width 0.1)
				(type default)
			)
			(layer "B.Fab")
		)
		(pad "1" smd circle
			(at 0.40005 0 180)
			(size 0 0)
			(layers "B.Cu" "B.Mask" "B.Paste")
			(net "P3V3_AUX")
		)
		(pad "2" smd circle
			(at -0.40005 0 180)
			(size 0 0)
			(layers "B.Cu" "B.Mask" "B.Paste")
			(net "GND")
		)
	)
	(footprint ""
		(layer "B.Cu")
		(at 183.3499 -301.599854 -90)
		(property "Reference" "C1450"
			(at 0 0 90)
			(layer "B.SilkS")
			(hide yes)
			(effects
				(font
					(size 1.27 1.27)
				)
				(justify mirror)
			)
		)
		(property "Value" ""
			(at 0 0 90)
			(layer "B.Fab")
			(effects
				(font
					(size 1.27 1.27)
				)
				(justify mirror)
			)
		)
		(duplicate_pad_numbers_are_jumpers no)
		(fp_line
			(start -0.299974 0.150114)
			(end 0.299974 0.150114)
			(stroke
				(width 0.1)
				(type default)
			)
			(layer "B.Fab")
		)
		(fp_line
			(start 0.299974 0.150114)
			(end 0.299974 -0.150114)
			(stroke
				(width 0.1)
				(type default)
			)
			(layer "B.Fab")
		)
		(fp_line
			(start -0.299974 -0.150114)
			(end -0.299974 0.150114)
			(stroke
				(width 0.1)
				(type default)
			)
			(layer "B.Fab")
		)
		(fp_line
			(start 0.299974 -0.150114)
			(end -0.299974 -0.150114)
			(stroke
				(width 0.1)
				(type default)
			)
			(layer "B.Fab")
		)
		(pad "1" smd rect
			(at 0.2667 0 90)
			(size 0.3048 0.381)
			(layers "B.Cu" "B.Mask" "B.Paste")
			(net "P0V8_SERDES_VDDA_PEX1")
		)
		(pad "2" smd rect
			(at -0.2667 0 90)
			(size 0.3048 0.381)
			(layers "B.Cu" "B.Mask" "B.Paste")
			(net "GND")
		)
	)
	(footprint ""
		(layer "B.Cu")
		(at 281.348942 -301.0154 180)
		(property "Reference" "C1639"
			(at 0 0 0)
			(layer "B.SilkS")
			(hide yes)
			(effects
				(font
					(size 1.27 1.27)
				)
				(justify mirror)
			)
		)
		(property "Value" ""
			(at 0 0 0)
			(layer "B.Fab")
			(effects
				(font
					(size 1.27 1.27)
				)
				(justify mirror)
			)
		)
		(duplicate_pad_numbers_are_jumpers no)
		(fp_line
			(start 0.299974 0.150114)
			(end 0.299974 -0.150114)
			(stroke
				(width 0.1)
				(type default)
			)
			(layer "B.Fab")
		)
		(fp_line
			(start 0.299974 -0.150114)
			(end -0.299974 -0.150114)
			(stroke
				(width 0.1)
				(type default)
			)
			(layer "B.Fab")
		)
		(fp_line
			(start -0.299974 0.150114)
			(end 0.299974 0.150114)
			(stroke
				(width 0.1)
				(type default)
			)
			(layer "B.Fab")
		)
		(fp_line
			(start -0.299974 -0.150114)
			(end -0.299974 0.150114)
			(stroke
				(width 0.1)
				(type default)
			)
			(layer "B.Fab")
		)
		(pad "1" smd rect
			(at 0.2667 0)
			(size 0.3048 0.381)
			(layers "B.Cu" "B.Mask" "B.Paste")
			(net "P0V8_PEX2")
		)
		(pad "2" smd rect
			(at -0.2667 0)
			(size 0.3048 0.381)
			(layers "B.Cu" "B.Mask" "B.Paste")
			(net "GND")
		)
	)
	(footprint ""
		(layer "B.Cu")
		(at 221.257114 -208.832704)
		(property "Reference" "C2012"
			(at 0 0 0)
			(layer "B.SilkS")
			(hide yes)
			(effects
				(font
					(size 1.27 1.27)
				)
				(justify mirror)
			)
		)
		(property "Value" ""
			(at 0 0 0)
			(layer "B.Fab")
			(effects
				(font
					(size 1.27 1.27)
				)
				(justify mirror)
			)
		)
		(duplicate_pad_numbers_are_jumpers no)
		(fp_line
			(start -1.2954 -0.5842)
			(end -1.2954 0.5842)
			(stroke
				(width 0.1524)
				(type default)
			)
			(layer "B.SilkS")
		)
		(fp_line
			(start -1.2954 0.5842)
			(end 1.2954 0.5842)
			(stroke
				(width 0.1524)
				(type default)
			)
			(layer "B.SilkS")
		)
		(fp_line
			(start 1.2954 -0.5842)
			(end -1.2954 -0.5842)
			(stroke
				(width 0.1524)
				(type default)
			)
			(layer "B.SilkS")
		)
		(fp_line
			(start 1.2954 0.5842)
			(end 1.2954 -0.5842)
			(stroke
				(width 0.1524)
				(type default)
			)
			(layer "B.SilkS")
		)
		(fp_line
			(start -1.1938 -0.4064)
			(end -1.1938 0.4064)
			(stroke
				(width 0.1)
				(type default)
			)
			(layer "B.Fab")
		)
		(fp_line
			(start -1.1938 0.4064)
			(end -0.8636 0.4064)
			(stroke
				(width 0.1)
				(type default)
			)
			(layer "B.Fab")
		)
		(fp_line
			(start -0.8636 -0.4572)
			(end -0.8636 -0.4064)
			(stroke
				(width 0.1)
				(type default)
			)
			(layer "B.Fab")
		)
		(fp_line
			(start -0.8636 -0.4064)
			(end -1.1938 -0.4064)
			(stroke
				(width 0.1)
				(type default)
			)
			(layer "B.Fab")
		)
		(fp_line
			(start -0.8636 0.4064)
			(end -0.8636 0.4572)
			(stroke
				(width 0.1)
				(type default)
			)
			(layer "B.Fab")
		)
		(fp_line
			(start -0.8636 0.4572)
			(end 0.8636 0.4572)
			(stroke
				(width 0.1)
				(type default)
			)
			(layer "B.Fab")
		)
		(fp_line
			(start 0.8636 -0.4572)
			(end -0.8636 -0.4572)
			(stroke
				(width 0.1)
				(type default)
			)
			(layer "B.Fab")
		)
		(fp_line
			(start 0.8636 -0.4064)
			(end 0.8636 -0.4572)
			(stroke
				(width 0.1)
				(type default)
			)
			(layer "B.Fab")
		)
		(fp_line
			(start 0.8636 0.4064)
			(end 1.1938 0.4064)
			(stroke
				(width 0.1)
				(type default)
			)
			(layer "B.Fab")
		)
		(fp_line
			(start 0.8636 0.4572)
			(end 0.8636 0.4064)
			(stroke
				(width 0.1)
				(type default)
			)
			(layer "B.Fab")
		)
		(fp_line
			(start 1.1938 -0.4064)
			(end 0.8636 -0.4064)
			(stroke
				(width 0.1)
				(type default)
			)
			(layer "B.Fab")
		)
		(fp_line
			(start 1.1938 0.4064)
			(end 1.1938 -0.4064)
			(stroke
				(width 0.1)
				(type default)
			)
			(layer "B.Fab")
		)
		(pad "1" smd rect
			(at 0.7366 0 270)
			(size 0.7112 0.8128)
			(layers "B.Cu" "B.Mask" "B.Paste")
			(net "P3V3_AUX")
		)
		(pad "2" smd rect
			(at -0.7366 0 270)
			(size 0.7112 0.8128)
			(layers "B.Cu" "B.Mask" "B.Paste")
			(net "GND")
		)
	)
	(footprint ""
		(layer "B.Cu")
		(at 405.575008 -297.79976 90)
		(property "Reference" "C1919"
			(at 0 0 90)
			(layer "B.SilkS")
			(hide yes)
			(effects
				(font
					(size 1.27 1.27)
				)
				(justify mirror)
			)
		)
		(property "Value" ""
			(at 0 0 90)
			(layer "B.Fab")
			(effects
				(font
					(size 1.27 1.27)
				)
				(justify mirror)
			)
		)
		(duplicate_pad_numbers_are_jumpers no)
		(fp_line
			(start 0.299974 -0.150114)
			(end -0.299974 -0.150114)
			(stroke
				(width 0.1)
				(type default)
			)
			(layer "B.Fab")
		)
		(fp_line
			(start -0.299974 -0.150114)
			(end -0.299974 0.150114)
			(stroke
				(width 0.1)
				(type default)
			)
			(layer "B.Fab")
		)
		(fp_line
			(start 0.299974 0.150114)
			(end 0.299974 -0.150114)
			(stroke
				(width 0.1)
				(type default)
			)
			(layer "B.Fab")
		)
		(fp_line
			(start -0.299974 0.150114)
			(end 0.299974 0.150114)
			(stroke
				(width 0.1)
				(type default)
			)
			(layer "B.Fab")
		)
		(pad "1" smd rect
			(at 0.2667 0 270)
			(size 0.3048 0.381)
			(layers "B.Cu" "B.Mask" "B.Paste")
			(net "P0V8_PEX3")
		)
		(pad "2" smd rect
			(at -0.2667 0 270)
			(size 0.3048 0.381)
			(layers "B.Cu" "B.Mask" "B.Paste")
			(net "GND")
		)
	)
)
